# S9S_MB_2U (Grand Teton) — schematic netlist excerpt (pin names and nets, part order shuffled) for the footprints in the layout excerpt that follows; sources: Cadence DE-HDL packaged netlist, KiCad conversion of 03242023_DA0F0TMBIJ0_F0T_Motherboard_J_brd_V01_OCP.brd

J107  CONN112_10137002101LF  CONN112_10137002-101LF IO  pkg HSD_F112D8_P2W1-2_RDH  page 138
  A1  = NC_J107_A1
  A2  = GND
  A3  = NC_J107_A3
  A4  = GND
  A5  = NC_J107_A5
  A6  = GND
  A7  = SWB_HSC_PWRGD
  A8  = GND
  B1  = GND
  B2  = P5E_CPU0_PE0_RX_DN<6>
  B3  = GND
  B4  = P5E_CPU0_PE0_RX_DN<4>
  B5  = GND
  B6  = P5E_CPU0_PE0_RX_DN<2>
  B7  = GND
  B8  = P5E_CPU0_PE0_RX_DN<0>
  C1  = P5E_CPU0_PE0_RX_DN<7>
  C2  = P5E_CPU0_PE0_RX_DP<6>
  C3  = P5E_CPU0_PE0_RX_DN<5>
  C4  = P5E_CPU0_PE0_RX_DP<4>
  C5  = P5E_CPU0_PE0_RX_DP<3>
  C6  = P5E_CPU0_PE0_RX_DP<2>
  C7  = P5E_CPU0_PE0_RX_DP<1>
  C8  = P5E_CPU0_PE0_RX_DP<0>
  D1  = P5E_CPU0_PE0_RX_DP<7>
  D2  = GND
  D3  = P5E_CPU0_PE0_RX_DP<5>
  D4  = GND
  D5  = P5E_CPU0_PE0_RX_DN<3>
  D6  = GND
  D7  = P5E_CPU0_PE0_RX_DN<1>
  D8  = GND
  E1  = GND
  E2  = P5E_CPU0_PE4_RX_DP<9>
  E3  = GND
  E4  = P5E_CPU0_PE4_RX_DP<11>
  E5  = GND
  E6  = P5E_CPU0_PE4_RX_DP<13>
  E7  = GND
  E8  = P5E_CPU0_PE4_RX_DP<15>
  F1  = P5E_CPU0_PE4_RX_DN<8>
  F2  = P5E_CPU0_PE4_RX_DN<9>
  F3  = P5E_CPU0_PE4_RX_DN<10>
  F4  = P5E_CPU0_PE4_RX_DN<11>
  F5  = P5E_CPU0_PE4_RX_DN<12>
  F6  = P5E_CPU0_PE4_RX_DN<13>
  F7  = P5E_CPU0_PE4_RX_DN<14>
  F8  = P5E_CPU0_PE4_RX_DN<15>
  G1  = P5E_CPU0_PE4_RX_DP<8>
  G2  = GND
  G3  = P5E_CPU0_PE4_RX_DP<10>
  G4  = GND
  G5  = P5E_CPU0_PE4_RX_DP<12>
  G6  = GND
  G7  = P5E_CPU0_PE4_RX_DP<14>
  G8  = GND
  H1  = GND
  H2  = P5E_CPU0_PE0_TX_C_DN<6>
  H3  = GND
  H4  = P5E_CPU0_PE0_TX_C_DN<4>
  H5  = GND
  H6  = P5E_CPU0_PE0_TX_C_DN<2>
  H7  = GND
  H8  = P5E_CPU0_PE0_TX_C_DN<0>
  I1  = P5E_CPU0_PE0_TX_C_DN<7>
  I2  = P5E_CPU0_PE0_TX_C_DP<6>
  I3  = P5E_CPU0_PE0_TX_C_DN<5>
  I4  = P5E_CPU0_PE0_TX_C_DP<4>
  I5  = P5E_CPU0_PE0_TX_C_DN<3>
  I6  = P5E_CPU0_PE0_TX_C_DP<2>
  I7  = P5E_CPU0_PE0_TX_C_DN<1>
  I8  = P5E_CPU0_PE0_TX_C_DP<0>
  J1  = P5E_CPU0_PE0_TX_C_DP<7>
  J2  = GND
  J3  = P5E_CPU0_PE0_TX_C_DP<5>
  J4  = GND
  J5  = P5E_CPU0_PE0_TX_C_DP<3>
  J6  = GND
  J7  = P5E_CPU0_PE0_TX_C_DP<1>
  J8  = GND
  K1  = GND
  K2  = P5E_CPU0_PE4_TX_C_DN<9>
  K3  = GND
  K4  = P5E_CPU0_PE4_TX_C_DP<11>
  K5  = GND
  K6  = P5E_CPU0_PE4_TX_C_DN<13>
  K7  = GND
  K8  = P5E_CPU0_PE4_TX_C_DN<15>
  L1  = P5E_CPU0_PE4_TX_C_DN<8>
  L2  = P5E_CPU0_PE4_TX_C_DP<9>
  L3  = P5E_CPU0_PE4_TX_C_DN<10>
  L4  = P5E_CPU0_PE4_TX_C_DN<11>
  L5  = P5E_CPU0_PE4_TX_C_DN<12>
  L6  = P5E_CPU0_PE4_TX_C_DP<13>
  L7  = P5E_CPU0_PE4_TX_C_DN<14>
  L8  = P5E_CPU0_PE4_TX_C_DP<15>
  M1  = P5E_CPU0_PE4_TX_C_DP<8>
  M2  = GND
  M3  = P5E_CPU0_PE4_TX_C_DP<10>
  M4  = GND
  M5  = P5E_CPU0_PE4_TX_C_DP<12>
  M6  = GND
  M7  = P5E_CPU0_PE4_TX_C_DP<14>
  M8  = GND
  N1  = GND
  N2  = PRSNT_CABLE_SWB_B2_N
  N3  = GND
  N4  = NC_J107_N4
  N5  = GND
  N6  = NC_J107_N6
  N7  = GND
  N8  = SWB_HSC_EN_BUF

(kicad_pcb
	(version 20260206)
	(generator "pcbnew")
	(generator_version "10.0")
	(general
		(thickness 1.6)
		(legacy_teardrops no)
	)
	(paper "A4")
	(title_block
		(title "03242023_DA0F0TMBIJ0_F0T_Motherboard_J_brd_V01_OCP.brd")
		(comment 1 "Grand Teton / footprint 950 of 6105 (J107), pads 1-31 of 48")
	)
	(layers
		(0 "F.Cu" signal "TOP")
		(4 "In1.Cu" signal "GND")
		(6 "In2.Cu" signal "IN1")
		(8 "In3.Cu" signal "GND1")
		(10 "In4.Cu" signal "IN2")
		(12 "In5.Cu" signal "GND2")
		(14 "In6.Cu" signal "IN3")
		(16 "In7.Cu" signal "GND3")
		(18 "In8.Cu" signal "VCC")
		(20 "In9.Cu" signal "VCC1")
		(22 "In10.Cu" signal "GND4")
		(24 "In11.Cu" signal "IN4")
		(26 "In12.Cu" signal "GND5")
		(28 "In13.Cu" signal "IN5")
		(30 "In14.Cu" signal "GND6")
		(32 "In15.Cu" signal "IN6")
		(34 "In16.Cu" signal "GND7")
		(2 "B.Cu" signal "BOTTOM")
		(9 "F.Adhes" user "F.Adhesive")
		(11 "B.Adhes" user "B.Adhesive")
		(13 "F.Paste" user "Package Geometry/Pastemask Top")
		(15 "B.Paste" user "Package Geometry/Pastemask Bottom")
		(5 "F.SilkS" user "Ref Des/Silkscreen Top")
		(7 "B.SilkS" user "Ref Des/Silkscreen Bottom")
		(1 "F.Mask" user "Board Geometry/Soldermask Top")
		(3 "B.Mask" user "Board Geometry/Soldermask Bottom")
		(17 "Dwgs.User" user "User.Drawings")
		(19 "Cmts.User" user "User.Comments")
		(21 "Eco1.User" user "User.Eco1")
		(23 "Eco2.User" user "User.Eco2")
		(25 "Edge.Cuts" user "Board Geometry/Outline")
		(27 "Margin" user)
		(31 "F.CrtYd" user "Package Geometry/Place Bound Top")
		(29 "B.CrtYd" user "Package Geometry/Place Bound Bottom")
		(35 "F.Fab" user "Ref Des/Assembly Top")
		(33 "B.Fab" user "Ref Des/Assembly Bottom")
	)
	(footprint ""
		(layer "F.Cu")
		(at 331.650086 -440.489848)
		(property "Reference" "J107"
			(at 3.42392 23.088092 0)
			(unlocked yes)
			(layer "F.SilkS")
			(effects
				(font
					(size 0.7874 0.5842)
					(thickness 0.1524)
				)
				(justify left)
			)
		)
		(property "Value" ""
			(at 0 0 0)
			(layer "F.Fab")
			(effects
				(font
					(size 1.27 1.27)
				)
			)
		)
		(duplicate_pad_numbers_are_jumpers no)
		(pad "A1" thru_hole rect
			(at 0 0 180)
			(size 0.766318 0.766318)
			(drill 0.359918)
			(layers "*.Cu" "*.Mask")
			(remove_unused_layers no)
			(net "NC_J107_A1")
			(clearance 0.0508)
			(thermal_gap 0.0508)
			(padstack
				(mode front_inner_back)
				(layer "Inner"
					(shape circle)
					(size 0.766318 0.766318)
					(clearance 0.0508)
				)
				(layer "B.Cu"
					(shape rect)
					(size 0.766318 0.766318)
					(clearance 0.0508)
				)
			)
		)
		(pad "A2" thru_hole circle
			(at 1.999996 0.199898 180)
			(size 0.906272 0.906272)
			(drill 0.499872)
			(layers "*.Cu" "*.Mask")
			(remove_unused_layers no)
			(net "GND")
			(clearance 0.0508)
			(thermal_gap 0.0508)
		)
		(pad "A3" thru_hole circle
			(at 3.999992 0 180)
			(size 0.766318 0.766318)
			(drill 0.359918)
			(layers "*.Cu" "*.Mask")
			(remove_unused_layers no)
			(net "NC_J107_A3")
			(clearance 0.0508)
			(thermal_gap 0.0508)
		)
		(pad "A4" thru_hole circle
			(at 5.999988 0.199898 180)
			(size 0.906272 0.906272)
			(drill 0.499872)
			(layers "*.Cu" "*.Mask")
			(remove_unused_layers no)
			(net "GND")
			(clearance 0.0508)
			(thermal_gap 0.0508)
		)
		(pad "A5" thru_hole circle
			(at 7.999984 0 180)
			(size 0.766318 0.766318)
			(drill 0.359918)
			(layers "*.Cu" "*.Mask")
			(remove_unused_layers no)
			(net "NC_J107_A5")
			(clearance 0.0508)
			(thermal_gap 0.0508)
		)
		(pad "A6" thru_hole circle
			(at 9.99998 0.199898 180)
			(size 0.906272 0.906272)
			(drill 0.499872)
			(layers "*.Cu" "*.Mask")
			(remove_unused_layers no)
			(net "GND")
			(clearance 0.0508)
			(thermal_gap 0.0508)
		)
		(pad "A7" thru_hole circle
			(at 11.999976 0 180)
			(size 0.766318 0.766318)
			(drill 0.359918)
			(layers "*.Cu" "*.Mask")
			(remove_unused_layers no)
			(net "SWB_HSC_PWRGD")
			(clearance 0.0508)
			(thermal_gap 0.0508)
		)
		(pad "A8" thru_hole circle
			(at 13.999972 0.199898 180)
			(size 0.906272 0.906272)
			(drill 0.499872)
			(layers "*.Cu" "*.Mask")
			(remove_unused_layers no)
			(net "GND")
			(clearance 0.0508)
			(thermal_gap 0.0508)
		)
		(pad "B1" thru_hole circle
			(at 0 1.199896 180)
			(size 0.906272 0.906272)
			(drill 0.499872)
			(layers "*.Cu" "*.Mask")
			(remove_unused_layers no)
			(net "GND")
			(clearance 0.0508)
			(thermal_gap 0.0508)
		)
		(pad "B3" thru_hole circle
			(at 3.999992 1.199896 180)
			(size 0.906272 0.906272)
			(drill 0.499872)
			(layers "*.Cu" "*.Mask")
			(remove_unused_layers no)
			(net "GND")
			(clearance 0.0508)
			(thermal_gap 0.0508)
		)
		(pad "B5" thru_hole circle
			(at 7.999984 1.199896 180)
			(size 0.906272 0.906272)
			(drill 0.499872)
			(layers "*.Cu" "*.Mask")
			(remove_unused_layers no)
			(net "GND")
			(clearance 0.0508)
			(thermal_gap 0.0508)
		)
		(pad "B7" thru_hole circle
			(at 11.999976 1.199896 180)
			(size 0.906272 0.906272)
			(drill 0.499872)
			(layers "*.Cu" "*.Mask")
			(remove_unused_layers no)
			(net "GND")
			(clearance 0.0508)
			(thermal_gap 0.0508)
		)
		(pad "D2" thru_hole circle
			(at 1.999996 3.800094 180)
			(size 0.906272 0.906272)
			(drill 0.499872)
			(layers "*.Cu" "*.Mask")
			(remove_unused_layers no)
			(net "GND")
			(clearance 0.0508)
			(thermal_gap 0.0508)
		)
		(pad "D4" thru_hole circle
			(at 5.999988 3.800094 180)
			(size 0.906272 0.906272)
			(drill 0.499872)
			(layers "*.Cu" "*.Mask")
			(remove_unused_layers no)
			(net "GND")
			(clearance 0.0508)
			(thermal_gap 0.0508)
		)
		(pad "D6" thru_hole circle
			(at 9.99998 3.800094 180)
			(size 0.906272 0.906272)
			(drill 0.499872)
			(layers "*.Cu" "*.Mask")
			(remove_unused_layers no)
			(net "GND")
			(clearance 0.0508)
			(thermal_gap 0.0508)
		)
		(pad "D8" thru_hole circle
			(at 13.999972 3.800094 180)
			(size 0.906272 0.906272)
			(drill 0.499872)
			(layers "*.Cu" "*.Mask")
			(remove_unused_layers no)
			(net "GND")
			(clearance 0.0508)
			(thermal_gap 0.0508)
		)
		(pad "E1" thru_hole circle
			(at 0 4.800092 180)
			(size 0.906272 0.906272)
			(drill 0.499872)
			(layers "*.Cu" "*.Mask")
			(remove_unused_layers no)
			(net "GND")
			(clearance 0.0508)
			(thermal_gap 0.0508)
		)
		(pad "E3" thru_hole circle
			(at 3.999992 4.800092 180)
			(size 0.906272 0.906272)
			(drill 0.499872)
			(layers "*.Cu" "*.Mask")
			(remove_unused_layers no)
			(net "GND")
			(clearance 0.0508)
			(thermal_gap 0.0508)
		)
		(pad "E5" thru_hole circle
			(at 7.999984 4.800092 180)
			(size 0.906272 0.906272)
			(drill 0.499872)
			(layers "*.Cu" "*.Mask")
			(remove_unused_layers no)
			(net "GND")
			(clearance 0.0508)
			(thermal_gap 0.0508)
		)
		(pad "E7" thru_hole circle
			(at 11.999976 4.800092 180)
			(size 0.906272 0.906272)
			(drill 0.499872)
			(layers "*.Cu" "*.Mask")
			(remove_unused_layers no)
			(net "GND")
			(clearance 0.0508)
			(thermal_gap 0.0508)
		)
		(pad "G2" thru_hole circle
			(at 1.999996 7.400036 180)
			(size 0.906272 0.906272)
			(drill 0.499872)
			(layers "*.Cu" "*.Mask")
			(remove_unused_layers no)
			(net "GND")
			(clearance 0.0508)
			(thermal_gap 0.0508)
		)
		(pad "G4" thru_hole circle
			(at 5.999988 7.400036 180)
			(size 0.906272 0.906272)
			(drill 0.499872)
			(layers "*.Cu" "*.Mask")
			(remove_unused_layers no)
			(net "GND")
			(clearance 0.0508)
			(thermal_gap 0.0508)
		)
		(pad "G6" thru_hole circle
			(at 9.99998 7.400036 180)
			(size 0.906272 0.906272)
			(drill 0.499872)
			(layers "*.Cu" "*.Mask")
			(remove_unused_layers no)
			(net "GND")
			(clearance 0.0508)
			(thermal_gap 0.0508)
		)
		(pad "G8" thru_hole circle
			(at 13.999972 7.400036 180)
			(size 0.906272 0.906272)
			(drill 0.499872)
			(layers "*.Cu" "*.Mask")
			(remove_unused_layers no)
			(net "GND")
			(clearance 0.0508)
			(thermal_gap 0.0508)
		)
		(pad "H1" thru_hole circle
			(at 0 8.400034 180)
			(size 0.906272 0.906272)
			(drill 0.499872)
			(layers "*.Cu" "*.Mask")
			(remove_unused_layers no)
			(net "GND")
			(clearance 0.0508)
			(thermal_gap 0.0508)
		)
		(pad "H3" thru_hole circle
			(at 3.999992 8.400034 180)
			(size 0.906272 0.906272)
			(drill 0.499872)
			(layers "*.Cu" "*.Mask")
			(remove_unused_layers no)
			(net "GND")
			(clearance 0.0508)
			(thermal_gap 0.0508)
		)
		(pad "H5" thru_hole circle
			(at 7.999984 8.400034 180)
			(size 0.906272 0.906272)
			(drill 0.499872)
			(layers "*.Cu" "*.Mask")
			(remove_unused_layers no)
			(net "GND")
			(clearance 0.0508)
			(thermal_gap 0.0508)
		)
		(pad "H7" thru_hole circle
			(at 11.999976 8.400034 180)
			(size 0.906272 0.906272)
			(drill 0.499872)
			(layers "*.Cu" "*.Mask")
			(remove_unused_layers no)
			(net "GND")
			(clearance 0.0508)
			(thermal_gap 0.0508)
		)
		(pad "J2" thru_hole circle
			(at 1.999996 10.999978 180)
			(size 0.906272 0.906272)
			(drill 0.499872)
			(layers "*.Cu" "*.Mask")
			(remove_unused_layers no)
			(net "GND")
			(clearance 0.0508)
			(thermal_gap 0.0508)
		)
		(pad "J4" thru_hole circle
			(at 5.999988 10.999978 180)
			(size 0.906272 0.906272)
			(drill 0.499872)
			(layers "*.Cu" "*.Mask")
			(remove_unused_layers no)
			(net "GND")
			(clearance 0.0508)
			(thermal_gap 0.0508)
		)
		(pad "J6" thru_hole circle
			(at 9.99998 10.999978 180)
			(size 0.906272 0.906272)
			(drill 0.499872)
			(layers "*.Cu" "*.Mask")
			(remove_unused_layers no)
			(net "GND")
			(clearance 0.0508)
			(thermal_gap 0.0508)
		)
	)
)
